(kicad_pcb
	(version 20260206)
	(generator "pcbnew")
	(generator_version "10.0")
	(general
		(thickness 1.6)
		(legacy_teardrops no)
	)
	(paper "A4")
	(title_block
		(title "01162023_DA0F0TEBIF0_F0T_Expander_BD_F_brd_V02_OCP.brd")
		(comment 1 "Grand Teton / footprints 7325-7335 of 9728")
	)
	(layers
		(0 "F.Cu" signal "TOP")
		(4 "In1.Cu" signal "GND")
		(6 "In2.Cu" signal "VCC")
		(8 "In3.Cu" signal "VCC1")
		(10 "In4.Cu" signal "GND1")
		(12 "In5.Cu" signal "IN1")
		(14 "In6.Cu" signal "GND2")
		(16 "In7.Cu" signal "IN2")
		(18 "In8.Cu" signal "GND3")
		(20 "In9.Cu" signal "IN3")
		(22 "In10.Cu" signal "GND4")
		(24 "In11.Cu" signal "IN4")
		(26 "In12.Cu" signal "GND5")
		(28 "In13.Cu" signal "IN5")
		(30 "In14.Cu" signal "GND6")
		(32 "In15.Cu" signal "IN6")
		(34 "In16.Cu" signal "GND7")
		(2 "B.Cu" signal "BOTTOM")
		(9 "F.Adhes" user "F.Adhesive")
		(11 "B.Adhes" user "B.Adhesive")
		(13 "F.Paste" user "Package Geometry/Pastemask Top")
		(15 "B.Paste" user "Package Geometry/Pastemask Bottom")
		(5 "F.SilkS" user "Ref Des/Silkscreen Top")
		(7 "B.SilkS" user "Ref Des/Silkscreen Bottom")
		(1 "F.Mask" user "Board Geometry/Soldermask Top")
		(3 "B.Mask" user "Board Geometry/Soldermask Bottom")
		(17 "Dwgs.User" user "User.Drawings")
		(19 "Cmts.User" user "User.Comments")
		(21 "Eco1.User" user "User.Eco1")
		(23 "Eco2.User" user "User.Eco2")
		(25 "Edge.Cuts" user "Board Geometry/Outline")
		(27 "Margin" user)
		(31 "F.CrtYd" user "Package Geometry/Place Bound Top")
		(29 "B.CrtYd" user "Package Geometry/Place Bound Bottom")
		(35 "F.Fab" user "Ref Des/Assembly Top")
		(33 "B.Fab" user "Ref Des/Assembly Bottom")
	)
	(footprint ""
		(layer "B.Cu")
		(at 309.741824 -98.021648 180)
		(property "Reference" "R268"
			(at 0 0 0)
			(layer "B.SilkS")
			(hide yes)
			(effects
				(font
					(size 1.27 1.27)
				)
				(justify mirror)
			)
		)
		(property "Value" ""
			(at 0 0 0)
			(layer "B.Fab")
			(effects
				(font
					(size 1.27 1.27)
				)
				(justify mirror)
			)
		)
		(duplicate_pad_numbers_are_jumpers no)
		(fp_line
			(start 0.7874 0.4064)
			(end 0.7874 -0.4064)
			(stroke
				(width 0.1524)
				(type default)
			)
			(layer "B.SilkS")
		)
		(fp_line
			(start 0.7874 -0.4064)
			(end -0.7874 -0.4064)
			(stroke
				(width 0.1524)
				(type default)
			)
			(layer "B.SilkS")
		)
		(fp_line
			(start -0.7874 0.4064)
			(end 0.7874 0.4064)
			(stroke
				(width 0.1524)
				(type default)
			)
			(layer "B.SilkS")
		)
		(fp_line
			(start -0.7874 -0.4064)
			(end -0.7874 0.4064)
			(stroke
				(width 0.1524)
				(type default)
			)
			(layer "B.SilkS")
		)
		(fp_line
			(start 0.67945 0.3048)
			(end 0.67945 -0.305054)
			(stroke
				(width 0.1)
				(type default)
			)
			(layer "B.Fab")
		)
		(fp_line
			(start 0.67945 -0.305054)
			(end 0.12065 -0.305054)
			(stroke
				(width 0.1)
				(type default)
			)
			(layer "B.Fab")
		)
		(fp_line
			(start 0.12065 0.3048)
			(end 0.67945 0.3048)
			(stroke
				(width 0.1)
				(type default)
			)
			(layer "B.Fab")
		)
		(fp_line
			(start 0.12065 0.2794)
			(end 0.12065 0.3048)
			(stroke
				(width 0.1)
				(type default)
			)
			(layer "B.Fab")
		)
		(fp_line
			(start 0.12065 -0.2794)
			(end -0.12065 -0.2794)
			(stroke
				(width 0.1)
				(type default)
			)
			(layer "B.Fab")
		)
		(fp_line
			(start 0.12065 -0.305054)
			(end 0.12065 -0.2794)
			(stroke
				(width 0.1)
				(type default)
			)
			(layer "B.Fab")
		)
		(fp_line
			(start -0.120396 0.3048)
			(end -0.120396 0.2794)
			(stroke
				(width 0.1)
				(type default)
			)
			(layer "B.Fab")
		)
		(fp_line
			(start -0.120396 0.2794)
			(end 0.12065 0.2794)
			(stroke
				(width 0.1)
				(type default)
			)
			(layer "B.Fab")
		)
		(fp_line
			(start -0.12065 -0.2794)
			(end -0.12065 -0.3048)
			(stroke
				(width 0.1)
				(type default)
			)
			(layer "B.Fab")
		)
		(fp_line
			(start -0.12065 -0.3048)
			(end -0.67945 -0.3048)
			(stroke
				(width 0.1)
				(type default)
			)
			(layer "B.Fab")
		)
		(fp_line
			(start -0.67945 0.3048)
			(end -0.120396 0.3048)
			(stroke
				(width 0.1)
				(type default)
			)
			(layer "B.Fab")
		)
		(fp_line
			(start -0.67945 -0.3048)
			(end -0.67945 0.3048)
			(stroke
				(width 0.1)
				(type default)
			)
			(layer "B.Fab")
		)
		(pad "1" smd circle
			(at 0.40005 0)
			(size 0 0)
			(layers "B.Cu" "B.Mask" "B.Paste")
			(net "NIC5_DATA_OUT")
		)
		(pad "2" smd circle
			(at -0.40005 0)
			(size 0 0)
			(layers "B.Cu" "B.Mask" "B.Paste")
			(net "GND")
		)
	)
	(footprint ""
		(layer "B.Cu")
		(at 353.842574 -260.509258 90)
		(property "Reference" "PR7139"
			(at 0 0 90)
			(layer "B.SilkS")
			(hide yes)
			(effects
				(font
					(size 1.27 1.27)
				)
				(justify mirror)
			)
		)
		(property "Value" ""
			(at 0 0 90)
			(layer "B.Fab")
			(effects
				(font
					(size 1.27 1.27)
				)
				(justify mirror)
			)
		)
		(duplicate_pad_numbers_are_jumpers no)
		(fp_line
			(start 0.7874 -0.4064)
			(end -0.7874 -0.4064)
			(stroke
				(width 0.1524)
				(type default)
			)
			(layer "B.SilkS")
		)
		(fp_line
			(start -0.7874 -0.4064)
			(end -0.7874 0.4064)
			(stroke
				(width 0.1524)
				(type default)
			)
			(layer "B.SilkS")
		)
		(fp_line
			(start 0.7874 0.4064)
			(end 0.7874 -0.4064)
			(stroke
				(width 0.1524)
				(type default)
			)
			(layer "B.SilkS")
		)
		(fp_line
			(start -0.7874 0.4064)
			(end 0.7874 0.4064)
			(stroke
				(width 0.1524)
				(type default)
			)
			(layer "B.SilkS")
		)
		(fp_line
			(start 0.67945 -0.305054)
			(end 0.12065 -0.305054)
			(stroke
				(width 0.1)
				(type default)
			)
			(layer "B.Fab")
		)
		(fp_line
			(start 0.12065 -0.305054)
			(end 0.12065 -0.2794)
			(stroke
				(width 0.1)
				(type default)
			)
			(layer "B.Fab")
		)
		(fp_line
			(start -0.12065 -0.3048)
			(end -0.67945 -0.3048)
			(stroke
				(width 0.1)
				(type default)
			)
			(layer "B.Fab")
		)
		(fp_line
			(start -0.67945 -0.3048)
			(end -0.67945 0.3048)
			(stroke
				(width 0.1)
				(type default)
			)
			(layer "B.Fab")
		)
		(fp_line
			(start 0.12065 -0.2794)
			(end -0.12065 -0.2794)
			(stroke
				(width 0.1)
				(type default)
			)
			(layer "B.Fab")
		)
		(fp_line
			(start -0.12065 -0.2794)
			(end -0.12065 -0.3048)
			(stroke
				(width 0.1)
				(type default)
			)
			(layer "B.Fab")
		)
		(fp_line
			(start 0.12065 0.2794)
			(end 0.12065 0.3048)
			(stroke
				(width 0.1)
				(type default)
			)
			(layer "B.Fab")
		)
		(fp_line
			(start -0.120396 0.2794)
			(end 0.12065 0.2794)
			(stroke
				(width 0.1)
				(type default)
			)
			(layer "B.Fab")
		)
		(fp_line
			(start 0.67945 0.3048)
			(end 0.67945 -0.305054)
			(stroke
				(width 0.1)
				(type default)
			)
			(layer "B.Fab")
		)
		(fp_line
			(start 0.12065 0.3048)
			(end 0.67945 0.3048)
			(stroke
				(width 0.1)
				(type default)
			)
			(layer "B.Fab")
		)
		(fp_line
			(start -0.120396 0.3048)
			(end -0.120396 0.2794)
			(stroke
				(width 0.1)
				(type default)
			)
			(layer "B.Fab")
		)
		(fp_line
			(start -0.67945 0.3048)
			(end -0.120396 0.3048)
			(stroke
				(width 0.1)
				(type default)
			)
			(layer "B.Fab")
		)
		(pad "1" smd circle
			(at 0.40005 0 270)
			(size 0 0)
			(layers "B.Cu" "B.Mask" "B.Paste")
			(net "NC_P0V8_PEX2_ISEN3")
		)
		(pad "2" smd circle
			(at -0.40005 0 270)
			(size 0 0)
			(layers "B.Cu" "B.Mask" "B.Paste")
			(net "GND")
		)
	)
	(footprint ""
		(layer "B.Cu")
		(at 160.549844 -298.74972)
		(property "Reference" "C3182"
			(at 0 0 0)
			(layer "B.SilkS")
			(hide yes)
			(effects
				(font
					(size 1.27 1.27)
				)
				(justify mirror)
			)
		)
		(property "Value" ""
			(at 0 0 0)
			(layer "B.Fab")
			(effects
				(font
					(size 1.27 1.27)
				)
				(justify mirror)
			)
		)
		(duplicate_pad_numbers_are_jumpers no)
		(fp_line
			(start -0.299974 -0.150114)
			(end -0.299974 0.150114)
			(stroke
				(width 0.1)
				(type default)
			)
			(layer "B.Fab")
		)
		(fp_line
			(start -0.299974 0.150114)
			(end 0.299974 0.150114)
			(stroke
				(width 0.1)
				(type default)
			)
			(layer "B.Fab")
		)
		(fp_line
			(start 0.299974 -0.150114)
			(end -0.299974 -0.150114)
			(stroke
				(width 0.1)
				(type default)
			)
			(layer "B.Fab")
		)
		(fp_line
			(start 0.299974 0.150114)
			(end 0.299974 -0.150114)
			(stroke
				(width 0.1)
				(type default)
			)
			(layer "B.Fab")
		)
		(pad "1" smd rect
			(at 0.2667 0 180)
			(size 0.3048 0.381)
			(layers "B.Cu" "B.Mask" "B.Paste")
			(net "P1V8_VDDA_PEX1")
		)
		(pad "2" smd rect
			(at -0.2667 0 180)
			(size 0.3048 0.381)
			(layers "B.Cu" "B.Mask" "B.Paste")
			(net "GND")
		)
	)
	(footprint ""
		(layer "B.Cu")
		(at 44.449746 -299.224954)
		(property "Reference" "C3009"
			(at 0 0 0)
			(layer "B.SilkS")
			(hide yes)
			(effects
				(font
					(size 1.27 1.27)
				)
				(justify mirror)
			)
		)
		(property "Value" ""
			(at 0 0 0)
			(layer "B.Fab")
			(effects
				(font
					(size 1.27 1.27)
				)
				(justify mirror)
			)
		)
		(duplicate_pad_numbers_are_jumpers no)
		(fp_line
			(start -0.299974 -0.150114)
			(end -0.299974 0.150114)
			(stroke
				(width 0.1)
				(type default)
			)
			(layer "B.Fab")
		)
		(fp_line
			(start -0.299974 0.150114)
			(end 0.299974 0.150114)
			(stroke
				(width 0.1)
				(type default)
			)
			(layer "B.Fab")
		)
		(fp_line
			(start 0.299974 -0.150114)
			(end -0.299974 -0.150114)
			(stroke
				(width 0.1)
				(type default)
			)
			(layer "B.Fab")
		)
		(fp_line
			(start 0.299974 0.150114)
			(end 0.299974 -0.150114)
			(stroke
				(width 0.1)
				(type default)
			)
			(layer "B.Fab")
		)
		(pad "1" smd rect
			(at 0.2667 0 180)
			(size 0.3048 0.381)
			(layers "B.Cu" "B.Mask" "B.Paste")
			(net "P1V8_VDDA_PEX0")
		)
		(pad "2" smd rect
			(at -0.2667 0 180)
			(size 0.3048 0.381)
			(layers "B.Cu" "B.Mask" "B.Paste")
			(net "GND")
		)
	)
	(footprint ""
		(layer "B.Cu")
		(at 53.474874 -286.399732 90)
		(property "Reference" "C2971"
			(at 0 0 90)
			(layer "B.SilkS")
			(hide yes)
			(effects
				(font
					(size 1.27 1.27)
				)
				(justify mirror)
			)
		)
		(property "Value" ""
			(at 0 0 90)
			(layer "B.Fab")
			(effects
				(font
					(size 1.27 1.27)
				)
				(justify mirror)
			)
		)
		(duplicate_pad_numbers_are_jumpers no)
		(fp_line
			(start 0.299974 -0.150114)
			(end -0.299974 -0.150114)
			(stroke
				(width 0.1)
				(type default)
			)
			(layer "B.Fab")
		)
		(fp_line
			(start -0.299974 -0.150114)
			(end -0.299974 0.150114)
			(stroke
				(width 0.1)
				(type default)
			)
			(layer "B.Fab")
		)
		(fp_line
			(start 0.299974 0.150114)
			(end 0.299974 -0.150114)
			(stroke
				(width 0.1)
				(type default)
			)
			(layer "B.Fab")
		)
		(fp_line
			(start -0.299974 0.150114)
			(end 0.299974 0.150114)
			(stroke
				(width 0.1)
				(type default)
			)
			(layer "B.Fab")
		)
		(pad "1" smd rect
			(at 0.2667 0 270)
			(size 0.3048 0.381)
			(layers "B.Cu" "B.Mask" "B.Paste")
			(net "P1V25_SERDES_VDDPLL_PEX0")
		)
		(pad "2" smd rect
			(at -0.2667 0 270)
			(size 0.3048 0.381)
			(layers "B.Cu" "B.Mask" "B.Paste")
			(net "GND")
		)
	)
	(footprint ""
		(layer "B.Cu")
		(at 59.649868 -303.499774 -90)
		(property "Reference" "C2906"
			(at 0 0 90)
			(layer "B.SilkS")
			(hide yes)
			(effects
				(font
					(size 1.27 1.27)
				)
				(justify mirror)
			)
		)
		(property "Value" ""
			(at 0 0 90)
			(layer "B.Fab")
			(effects
				(font
					(size 1.27 1.27)
				)
				(justify mirror)
			)
		)
		(duplicate_pad_numbers_are_jumpers no)
		(fp_line
			(start -0.299974 0.150114)
			(end 0.299974 0.150114)
			(stroke
				(width 0.1)
				(type default)
			)
			(layer "B.Fab")
		)
		(fp_line
			(start 0.299974 0.150114)
			(end 0.299974 -0.150114)
			(stroke
				(width 0.1)
				(type default)
			)
			(layer "B.Fab")
		)
		(fp_line
			(start -0.299974 -0.150114)
			(end -0.299974 0.150114)
			(stroke
				(width 0.1)
				(type default)
			)
			(layer "B.Fab")
		)
		(fp_line
			(start 0.299974 -0.150114)
			(end -0.299974 -0.150114)
			(stroke
				(width 0.1)
				(type default)
			)
			(layer "B.Fab")
		)
		(pad "1" smd rect
			(at 0.2667 0 90)
			(size 0.3048 0.381)
			(layers "B.Cu" "B.Mask" "B.Paste")
			(net "P1V25_PEX0")
		)
		(pad "2" smd rect
			(at -0.2667 0 90)
			(size 0.3048 0.381)
			(layers "B.Cu" "B.Mask" "B.Paste")
			(net "GND")
		)
	)
	(footprint ""
		(layer "B.Cu")
		(at 340.648798 -326.945498 -90)
		(property "Reference" "C4327"
			(at 0 0 90)
			(layer "B.SilkS")
			(hide yes)
			(effects
				(font
					(size 1.27 1.27)
				)
				(justify mirror)
			)
		)
		(property "Value" ""
			(at 0 0 90)
			(layer "B.Fab")
			(effects
				(font
					(size 1.27 1.27)
				)
				(justify mirror)
			)
		)
		(duplicate_pad_numbers_are_jumpers no)
		(fp_line
			(start -1.2954 0.5842)
			(end 1.2954 0.5842)
			(stroke
				(width 0.1524)
				(type default)
			)
			(layer "B.SilkS")
		)
		(fp_line
			(start 1.2954 0.5842)
			(end 1.2954 -0.5842)
			(stroke
				(width 0.1524)
				(type default)
			)
			(layer "B.SilkS")
		)
		(fp_line
			(start -1.2954 -0.5842)
			(end -1.2954 0.5842)
			(stroke
				(width 0.1524)
				(type default)
			)
			(layer "B.SilkS")
		)
		(fp_line
			(start 1.2954 -0.5842)
			(end -1.2954 -0.5842)
			(stroke
				(width 0.1524)
				(type default)
			)
			(layer "B.SilkS")
		)
		(fp_line
			(start -0.8636 0.4572)
			(end 0.8636 0.4572)
			(stroke
				(width 0.1)
				(type default)
			)
			(layer "B.Fab")
		)
		(fp_line
			(start 0.8636 0.4572)
			(end 0.8636 0.4064)
			(stroke
				(width 0.1)
				(type default)
			)
			(layer "B.Fab")
		)
		(fp_line
			(start -1.1938 0.4064)
			(end -0.8636 0.4064)
			(stroke
				(width 0.1)
				(type default)
			)
			(layer "B.Fab")
		)
		(fp_line
			(start -0.8636 0.4064)
			(end -0.8636 0.4572)
			(stroke
				(width 0.1)
				(type default)
			)
			(layer "B.Fab")
		)
		(fp_line
			(start 0.8636 0.4064)
			(end 1.1938 0.4064)
			(stroke
				(width 0.1)
				(type default)
			)
			(layer "B.Fab")
		)
		(fp_line
			(start 1.1938 0.4064)
			(end 1.1938 -0.4064)
			(stroke
				(width 0.1)
				(type default)
			)
			(layer "B.Fab")
		)
		(fp_line
			(start -1.1938 -0.4064)
			(end -1.1938 0.4064)
			(stroke
				(width 0.1)
				(type default)
			)
			(layer "B.Fab")
		)
		(fp_line
			(start -0.8636 -0.4064)
			(end -1.1938 -0.4064)
			(stroke
				(width 0.1)
				(type default)
			)
			(layer "B.Fab")
		)
		(fp_line
			(start 0.8636 -0.4064)
			(end 0.8636 -0.4572)
			(stroke
				(width 0.1)
				(type default)
			)
			(layer "B.Fab")
		)
		(fp_line
			(start 1.1938 -0.4064)
			(end 0.8636 -0.4064)
			(stroke
				(width 0.1)
				(type default)
			)
			(layer "B.Fab")
		)
		(fp_line
			(start -0.8636 -0.4572)
			(end -0.8636 -0.4064)
			(stroke
				(width 0.1)
				(type default)
			)
			(layer "B.Fab")
		)
		(fp_line
			(start 0.8636 -0.4572)
			(end -0.8636 -0.4572)
			(stroke
				(width 0.1)
				(type default)
			)
			(layer "B.Fab")
		)
		(pad "1" smd rect
			(at 0.7366 0 180)
			(size 0.7112 0.8128)
			(layers "B.Cu" "B.Mask" "B.Paste")
			(net "P0V8_SERDES_VDDA_PEX2_C9")
		)
		(pad "2" smd rect
			(at -0.7366 0 180)
			(size 0.7112 0.8128)
			(layers "B.Cu" "B.Mask" "B.Paste")
			(net "GND")
		)
	)
	(footprint ""
		(layer "B.Cu")
		(at 412.251398 -305.399948 -90)
		(property "Reference" "C3480"
			(at 0 0 90)
			(layer "B.SilkS")
			(hide yes)
			(effects
				(font
					(size 1.27 1.27)
				)
				(justify mirror)
			)
		)
		(property "Value" ""
			(at 0 0 90)
			(layer "B.Fab")
			(effects
				(font
					(size 1.27 1.27)
				)
				(justify mirror)
			)
		)
		(duplicate_pad_numbers_are_jumpers no)
		(fp_line
			(start -0.299974 0.150114)
			(end 0.299974 0.150114)
			(stroke
				(width 0.1)
				(type default)
			)
			(layer "B.Fab")
		)
		(fp_line
			(start 0.299974 0.150114)
			(end 0.299974 -0.150114)
			(stroke
				(width 0.1)
				(type default)
			)
			(layer "B.Fab")
		)
		(fp_line
			(start -0.299974 -0.150114)
			(end -0.299974 0.150114)
			(stroke
				(width 0.1)
				(type default)
			)
			(layer "B.Fab")
		)
		(fp_line
			(start 0.299974 -0.150114)
			(end -0.299974 -0.150114)
			(stroke
				(width 0.1)
				(type default)
			)
			(layer "B.Fab")
		)
		(pad "1" smd rect
			(at 0.2667 0 90)
			(size 0.3048 0.381)
			(layers "B.Cu" "B.Mask" "B.Paste")
			(net "P1V25_SERDES_VDDPLL_PEX3")
		)
		(pad "2" smd rect
			(at -0.2667 0 90)
			(size 0.3048 0.381)
			(layers "B.Cu" "B.Mask" "B.Paste")
			(net "GND")
		)
	)
	(footprint ""
		(layer "B.Cu")
		(at 46.355 -292.57498)
		(property "Reference" "C3056"
			(at 0 0 0)
			(layer "B.SilkS")
			(hide yes)
			(effects
				(font
					(size 1.27 1.27)
				)
				(justify mirror)
			)
		)
		(property "Value" ""
			(at 0 0 0)
			(layer "B.Fab")
			(effects
				(font
					(size 1.27 1.27)
				)
				(justify mirror)
			)
		)
		(duplicate_pad_numbers_are_jumpers no)
		(fp_line
			(start -0.299974 -0.150114)
			(end -0.299974 0.150114)
			(stroke
				(width 0.1)
				(type default)
			)
			(layer "B.Fab")
		)
		(fp_line
			(start -0.299974 0.150114)
			(end 0.299974 0.150114)
			(stroke
				(width 0.1)
				(type default)
			)
			(layer "B.Fab")
		)
		(fp_line
			(start 0.299974 -0.150114)
			(end -0.299974 -0.150114)
			(stroke
				(width 0.1)
				(type default)
			)
			(layer "B.Fab")
		)
		(fp_line
			(start 0.299974 0.150114)
			(end 0.299974 -0.150114)
			(stroke
				(width 0.1)
				(type default)
			)
			(layer "B.Fab")
		)
		(pad "1" smd rect
			(at 0.2667 0 180)
			(size 0.3048 0.381)
			(layers "B.Cu" "B.Mask" "B.Paste")
			(net "PCEPLL6_VDDA18_PEX0")
		)
		(pad "2" smd rect
			(at -0.2667 0 180)
			(size 0.3048 0.381)
			(layers "B.Cu" "B.Mask" "B.Paste")
			(net "GND")
		)
	)
	(footprint ""
		(layer "B.Cu")
		(at 285.674816 -297.79976 90)
		(property "Reference" "C1620"
			(at 0 0 90)
			(layer "B.SilkS")
			(hide yes)
			(effects
				(font
					(size 1.27 1.27)
				)
				(justify mirror)
			)
		)
		(property "Value" ""
			(at 0 0 90)
			(layer "B.Fab")
			(effects
				(font
					(size 1.27 1.27)
				)
				(justify mirror)
			)
		)
		(duplicate_pad_numbers_are_jumpers no)
		(fp_line
			(start 0.299974 -0.150114)
			(end -0.299974 -0.150114)
			(stroke
				(width 0.1)
				(type default)
			)
			(layer "B.Fab")
		)
		(fp_line
			(start -0.299974 -0.150114)
			(end -0.299974 0.150114)
			(stroke
				(width 0.1)
				(type default)
			)
			(layer "B.Fab")
		)
		(fp_line
			(start 0.299974 0.150114)
			(end 0.299974 -0.150114)
			(stroke
				(width 0.1)
				(type default)
			)
			(layer "B.Fab")
		)
		(fp_line
			(start -0.299974 0.150114)
			(end 0.299974 0.150114)
			(stroke
				(width 0.1)
				(type default)
			)
			(layer "B.Fab")
		)
		(pad "1" smd rect
			(at 0.2667 0 270)
			(size 0.3048 0.381)
			(layers "B.Cu" "B.Mask" "B.Paste")
			(net "P0V8_PEX2")
		)
		(pad "2" smd rect
			(at -0.2667 0 270)
			(size 0.3048 0.381)
			(layers "B.Cu" "B.Mask" "B.Paste")
			(net "GND")
		)
	)
	(footprint ""
		(layer "B.Cu")
		(at 403.199854 -292.099746 90)
		(property "Reference" "C1983"
			(at 0 0 90)
			(layer "B.SilkS")
			(hide yes)
			(effects
				(font
					(size 1.27 1.27)
				)
				(justify mirror)
			)
		)
		(property "Value" ""
			(at 0 0 90)
			(layer "B.Fab")
			(effects
				(font
					(size 1.27 1.27)
				)
				(justify mirror)
			)
		)
		(duplicate_pad_numbers_are_jumpers no)
		(fp_line
			(start 0.299974 -0.150114)
			(end -0.299974 -0.150114)
			(stroke
				(width 0.1)
				(type default)
			)
			(layer "B.Fab")
		)
		(fp_line
			(start -0.299974 -0.150114)
			(end -0.299974 0.150114)
			(stroke
				(width 0.1)
				(type default)
			)
			(layer "B.Fab")
		)
		(fp_line
			(start 0.299974 0.150114)
			(end 0.299974 -0.150114)
			(stroke
				(width 0.1)
				(type default)
			)
			(layer "B.Fab")
		)
		(fp_line
			(start -0.299974 0.150114)
			(end 0.299974 0.150114)
			(stroke
				(width 0.1)
				(type default)
			)
			(layer "B.Fab")
		)
		(pad "1" smd rect
			(at 0.2667 0 270)
			(size 0.3048 0.381)
			(layers "B.Cu" "B.Mask" "B.Paste")
			(net "P0V8_SERDES_VDDA_PEX3")
		)
		(pad "2" smd rect
			(at -0.2667 0 270)
			(size 0.3048 0.381)
			(layers "B.Cu" "B.Mask" "B.Paste")
			(net "GND")
		)
	)
)
